(kicad_pcb
	(version 20260206)
	(generator "pcbnew")
	(generator_version "10.0")
	(general
		(thickness 1.6)
		(legacy_teardrops no)
	)
	(paper "A4")
	(title_block
		(title "04192023_DAF0TMB3IC0_F0TG_MB_C_brd_V02_OCP.brd")
		(comment 1 "Grand Teton / footprints 1430-1436 of 8354")
	)
	(layers
		(0 "F.Cu" signal "TOP")
		(4 "In1.Cu" signal "GND")
		(6 "In2.Cu" signal "IN1")
		(8 "In3.Cu" signal "GND1")
		(10 "In4.Cu" signal "IN2")
		(12 "In5.Cu" signal "GND2")
		(14 "In6.Cu" signal "IN3")
		(16 "In7.Cu" signal "GND3")
		(18 "In8.Cu" signal "VCC")
		(20 "In9.Cu" signal "VCC1")
		(22 "In10.Cu" signal "GND4")
		(24 "In11.Cu" signal "IN4")
		(26 "In12.Cu" signal "GND5")
		(28 "In13.Cu" signal "IN5")
		(30 "In14.Cu" signal "GND6")
		(32 "In15.Cu" signal "IN6")
		(34 "In16.Cu" signal "GND7")
		(2 "B.Cu" signal "BOTTOM")
		(9 "F.Adhes" user "F.Adhesive")
		(11 "B.Adhes" user "B.Adhesive")
		(13 "F.Paste" user "Package Geometry/Pastemask Top")
		(15 "B.Paste" user "Package Geometry/Pastemask Bottom")
		(5 "F.SilkS" user "Ref Des/Silkscreen Top")
		(7 "B.SilkS" user "Ref Des/Silkscreen Bottom")
		(1 "F.Mask" user "Board Geometry/Soldermask Top")
		(3 "B.Mask" user "Board Geometry/Soldermask Bottom")
		(17 "Dwgs.User" user "User.Drawings")
		(19 "Cmts.User" user "User.Comments")
		(21 "Eco1.User" user "User.Eco1")
		(23 "Eco2.User" user "User.Eco2")
		(25 "Edge.Cuts" user "Board Geometry/Outline")
		(27 "Margin" user)
		(31 "F.CrtYd" user "Package Geometry/Place Bound Top")
		(29 "B.CrtYd" user "Package Geometry/Place Bound Bottom")
		(35 "F.Fab" user "Ref Des/Assembly Top")
		(33 "B.Fab" user "Ref Des/Assembly Bottom")
	)
	(footprint ""
		(layer "F.Cu")
		(at 215.4301 -408.084782)
		(property "Reference" "PR3988"
			(at 0 0 0)
			(layer "F.SilkS")
			(hide yes)
			(effects
				(font
					(size 1.27 1.27)
				)
			)
		)
		(property "Value" ""
			(at 0 0 0)
			(layer "F.Fab")
			(effects
				(font
					(size 1.27 1.27)
				)
			)
		)
		(duplicate_pad_numbers_are_jumpers no)
		(fp_line
			(start -0.7874 -0.4064)
			(end 0.7874 -0.4064)
			(stroke
				(width 0.1524)
				(type default)
			)
			(layer "F.SilkS")
		)
		(fp_line
			(start -0.7874 0.4064)
			(end -0.7874 -0.4064)
			(stroke
				(width 0.1524)
				(type default)
			)
			(layer "F.SilkS")
		)
		(fp_line
			(start 0.7874 -0.4064)
			(end 0.7874 0.4064)
			(stroke
				(width 0.1524)
				(type default)
			)
			(layer "F.SilkS")
		)
		(fp_line
			(start 0.7874 0.4064)
			(end -0.7874 0.4064)
			(stroke
				(width 0.1524)
				(type default)
			)
			(layer "F.SilkS")
		)
		(fp_line
			(start -0.67945 -0.305054)
			(end -0.12065 -0.305054)
			(stroke
				(width 0.1)
				(type default)
			)
			(layer "F.Fab")
		)
		(fp_line
			(start -0.67945 0.3048)
			(end -0.67945 -0.305054)
			(stroke
				(width 0.1)
				(type default)
			)
			(layer "F.Fab")
		)
		(fp_line
			(start -0.12065 -0.305054)
			(end -0.12065 -0.2794)
			(stroke
				(width 0.1)
				(type default)
			)
			(layer "F.Fab")
		)
		(fp_line
			(start -0.12065 -0.2794)
			(end 0.12065 -0.2794)
			(stroke
				(width 0.1)
				(type default)
			)
			(layer "F.Fab")
		)
		(fp_line
			(start -0.12065 0.2794)
			(end -0.12065 0.3048)
			(stroke
				(width 0.1)
				(type default)
			)
			(layer "F.Fab")
		)
		(fp_line
			(start -0.12065 0.3048)
			(end -0.67945 0.3048)
			(stroke
				(width 0.1)
				(type default)
			)
			(layer "F.Fab")
		)
		(fp_line
			(start 0.120396 0.2794)
			(end -0.12065 0.2794)
			(stroke
				(width 0.1)
				(type default)
			)
			(layer "F.Fab")
		)
		(fp_line
			(start 0.120396 0.3048)
			(end 0.120396 0.2794)
			(stroke
				(width 0.1)
				(type default)
			)
			(layer "F.Fab")
		)
		(fp_line
			(start 0.12065 -0.3048)
			(end 0.67945 -0.3048)
			(stroke
				(width 0.1)
				(type default)
			)
			(layer "F.Fab")
		)
		(fp_line
			(start 0.12065 -0.2794)
			(end 0.12065 -0.3048)
			(stroke
				(width 0.1)
				(type default)
			)
			(layer "F.Fab")
		)
		(fp_line
			(start 0.67945 -0.3048)
			(end 0.67945 0.3048)
			(stroke
				(width 0.1)
				(type default)
			)
			(layer "F.Fab")
		)
		(fp_line
			(start 0.67945 0.3048)
			(end 0.120396 0.3048)
			(stroke
				(width 0.1)
				(type default)
			)
			(layer "F.Fab")
		)
		(pad "1" smd circle
			(at -0.40005 0)
			(size 0 0)
			(layers "F.Cu" "F.Mask" "F.Paste")
			(net "HSC_SCREF")
		)
		(pad "2" smd circle
			(at 0.40005 0)
			(size 0 0)
			(layers "F.Cu" "F.Mask" "F.Paste")
			(net "HSC_SCREF_3")
		)
	)
	(footprint ""
		(layer "F.Cu")
		(at 161.337244 -375.49963 -90)
		(property "Reference" "C753"
			(at 0 0 270)
			(layer "F.SilkS")
			(hide yes)
			(effects
				(font
					(size 1.27 1.27)
				)
			)
		)
		(property "Value" ""
			(at 0 0 270)
			(layer "F.Fab")
			(effects
				(font
					(size 1.27 1.27)
				)
			)
		)
		(duplicate_pad_numbers_are_jumpers no)
		(fp_line
			(start -0.299974 0.150114)
			(end -0.299974 -0.150114)
			(stroke
				(width 0.1)
				(type default)
			)
			(layer "F.Fab")
		)
		(fp_line
			(start 0.299974 0.150114)
			(end -0.299974 0.150114)
			(stroke
				(width 0.1)
				(type default)
			)
			(layer "F.Fab")
		)
		(fp_line
			(start -0.299974 -0.150114)
			(end 0.299974 -0.150114)
			(stroke
				(width 0.1)
				(type default)
			)
			(layer "F.Fab")
		)
		(fp_line
			(start 0.299974 -0.150114)
			(end 0.299974 0.150114)
			(stroke
				(width 0.1)
				(type default)
			)
			(layer "F.Fab")
		)
		(pad "1" smd rect
			(at -0.2667 0 270)
			(size 0.3048 0.381)
			(layers "F.Cu" "F.Mask" "F.Paste")
			(net "P5E_CPU1_P2_TX_C_DP<10>")
		)
		(pad "2" smd rect
			(at 0.2667 0 270)
			(size 0.3048 0.381)
			(layers "F.Cu" "F.Mask" "F.Paste")
			(net "P5E_CPU1_P2_TX_DP<10>")
		)
	)
	(footprint ""
		(layer "F.Cu")
		(at 421.961564 -17.624298 90)
		(property "Reference" "C1571"
			(at 0 0 90)
			(layer "F.SilkS")
			(hide yes)
			(effects
				(font
					(size 1.27 1.27)
				)
			)
		)
		(property "Value" ""
			(at 0 0 90)
			(layer "F.Fab")
			(effects
				(font
					(size 1.27 1.27)
				)
			)
		)
		(duplicate_pad_numbers_are_jumpers no)
		(fp_line
			(start 0.299974 -0.150114)
			(end 0.299974 0.150114)
			(stroke
				(width 0.1)
				(type default)
			)
			(layer "F.Fab")
		)
		(fp_line
			(start -0.299974 -0.150114)
			(end 0.299974 -0.150114)
			(stroke
				(width 0.1)
				(type default)
			)
			(layer "F.Fab")
		)
		(fp_line
			(start 0.299974 0.150114)
			(end -0.299974 0.150114)
			(stroke
				(width 0.1)
				(type default)
			)
			(layer "F.Fab")
		)
		(fp_line
			(start -0.299974 0.150114)
			(end -0.299974 -0.150114)
			(stroke
				(width 0.1)
				(type default)
			)
			(layer "F.Fab")
		)
		(pad "1" smd rect
			(at -0.2667 0 90)
			(size 0.3048 0.381)
			(layers "F.Cu" "F.Mask" "F.Paste")
			(net "P5E_CPU0_G3_TX_C_DP<4>")
		)
		(pad "2" smd rect
			(at 0.2667 0 90)
			(size 0.3048 0.381)
			(layers "F.Cu" "F.Mask" "F.Paste")
			(net "P5E_CPU0_G3_TX_DP<4>")
		)
	)
	(footprint ""
		(layer "F.Cu")
		(at 234.739688 -159.997648 180)
		(property "Reference" "U154"
			(at -4.057904 -1.950212 0)
			(unlocked yes)
			(layer "F.SilkS")
			(effects
				(font
					(size 0.7874 0.5842)
					(thickness 0.1524)
				)
				(justify left)
			)
		)
		(property "Value" ""
			(at 0 0 180)
			(layer "F.Fab")
			(effects
				(font
					(size 1.27 1.27)
				)
			)
		)
		(duplicate_pad_numbers_are_jumpers no)
		(fp_line
			(start 1.0414 1.575054)
			(end -1.0414 1.575054)
			(stroke
				(width 0.1524)
				(type default)
			)
			(layer "F.SilkS")
		)
		(fp_line
			(start 1.0414 -1.575054)
			(end 1.0414 1.575054)
			(stroke
				(width 0.1524)
				(type default)
			)
			(layer "F.SilkS")
		)
		(fp_line
			(start 0.254 -1.575054)
			(end 1.0414 -1.575054)
			(stroke
				(width 0.1524)
				(type default)
			)
			(layer "F.SilkS")
		)
		(fp_line
			(start 0.2286 -1.575054)
			(end 0 -1.272032)
			(stroke
				(width 0.1524)
				(type default)
			)
			(layer "F.SilkS")
		)
		(fp_line
			(start 0 -1.272032)
			(end -0.254 -1.575054)
			(stroke
				(width 0.1524)
				(type default)
			)
			(layer "F.SilkS")
		)
		(fp_line
			(start -1.0414 1.575054)
			(end -1.0414 -1.575054)
			(stroke
				(width 0.1524)
				(type default)
			)
			(layer "F.SilkS")
		)
		(fp_line
			(start -1.0414 -1.575054)
			(end -0.254 -1.575054)
			(stroke
				(width 0.1524)
				(type default)
			)
			(layer "F.SilkS")
		)
		(fp_poly
			(pts
				(xy -3.443224 -1.397254) (xy -2.598928 -0.975106) (xy -3.443224 -0.552958)
			)
			(stroke
				(width 0)
				(type default)
			)
			(fill yes)
			(layer "F.SilkS")
		)
		(fp_line
			(start 2.5654 1.2192)
			(end 1.4478 1.2192)
			(stroke
				(width 0.1)
				(type default)
			)
			(layer "F.Fab")
		)
		(fp_line
			(start 2.5654 -1.2192)
			(end 2.5654 1.2192)
			(stroke
				(width 0.1)
				(type default)
			)
			(layer "F.Fab")
		)
		(fp_line
			(start 1.4478 1.5748)
			(end -1.4478 1.5748)
			(stroke
				(width 0.1)
				(type default)
			)
			(layer "F.Fab")
		)
		(fp_line
			(start 1.4478 1.2192)
			(end 1.4478 1.5748)
			(stroke
				(width 0.1)
				(type default)
			)
			(layer "F.Fab")
		)
		(fp_line
			(start 1.4478 -1.2192)
			(end 2.5654 -1.2192)
			(stroke
				(width 0.1)
				(type default)
			)
			(layer "F.Fab")
		)
		(fp_line
			(start 1.4478 -1.5748)
			(end 1.4478 -1.2192)
			(stroke
				(width 0.1)
				(type default)
			)
			(layer "F.Fab")
		)
		(fp_line
			(start -1.4478 1.5748)
			(end -1.4478 1.2192)
			(stroke
				(width 0.1)
				(type default)
			)
			(layer "F.Fab")
		)
		(fp_line
			(start -1.4478 1.2192)
			(end -2.5654 1.2192)
			(stroke
				(width 0.1)
				(type default)
			)
			(layer "F.Fab")
		)
		(fp_line
			(start -1.4478 -1.2192)
			(end -1.4478 -1.5748)
			(stroke
				(width 0.1)
				(type default)
			)
			(layer "F.Fab")
		)
		(fp_line
			(start -1.4478 -1.5748)
			(end 1.4478 -1.5748)
			(stroke
				(width 0.1)
				(type default)
			)
			(layer "F.Fab")
		)
		(fp_line
			(start -2.5654 1.2192)
			(end -2.5654 -1.2192)
			(stroke
				(width 0.1)
				(type default)
			)
			(layer "F.Fab")
		)
		(fp_line
			(start -2.5654 -1.2192)
			(end -1.4478 -1.2192)
			(stroke
				(width 0.1)
				(type default)
			)
			(layer "F.Fab")
		)
		(fp_poly
			(pts
				(xy -2.710688 -0.975106) (xy -3.726688 -1.483106) (xy -3.726688 -0.467106)
			)
			(stroke
				(width 0)
				(type default)
			)
			(fill yes)
			(layer "F.Fab")
		)
		(pad "1" smd rect
			(at -1.849882 -0.975106 90)
			(size 0.3556 1.3208)
			(layers "F.Cu" "F.Mask" "F.Paste")
			(net "JTAG_CPU1_TDO")
		)
		(pad "2" smd rect
			(at -1.849882 -0.32512 90)
			(size 0.3556 1.3208)
			(layers "F.Cu" "F.Mask" "F.Paste")
			(net "JTAG_CPUX_TDO_R")
		)
		(pad "3" smd rect
			(at -1.849882 0.32512 90)
			(size 0.3556 1.3208)
			(layers "F.Cu" "F.Mask" "F.Paste")
			(net "FM_PLD_CPU1_PRSNT_HDT_N")
		)
		(pad "4" smd rect
			(at -1.849882 0.975106 90)
			(size 0.3556 1.3208)
			(layers "F.Cu" "F.Mask" "F.Paste")
			(net "GND")
		)
		(pad "5" smd rect
			(at 1.849882 0.975106 90)
			(size 0.3556 1.3208)
			(layers "F.Cu" "F.Mask" "F.Paste")
			(net "JTAG_CPU1_BYPASS")
		)
		(pad "6" smd rect
			(at 1.849882 0.32512 90)
			(size 0.3556 1.3208)
			(layers "F.Cu" "F.Mask" "F.Paste")
			(net "JTAG_CPUX_TDO_R")
		)
		(pad "7" smd rect
			(at 1.849882 -0.32512 90)
			(size 0.3556 1.3208)
			(layers "F.Cu" "F.Mask" "F.Paste")
			(net "CPU1_HDT_BYPASS_SEL")
		)
		(pad "8" smd rect
			(at 1.849882 -0.975106 90)
			(size 0.3556 1.3208)
			(layers "F.Cu" "F.Mask" "F.Paste")
			(net "PVDD18_S5_P0")
		)
	)
	(footprint ""
		(layer "F.Cu")
		(at 272.728182 -351.573846 90)
		(property "Reference" "PC176_10"
			(at 0 0 90)
			(layer "F.SilkS")
			(hide yes)
			(effects
				(font
					(size 1.27 1.27)
				)
			)
		)
		(property "Value" ""
			(at 0 0 90)
			(layer "F.Fab")
			(effects
				(font
					(size 1.27 1.27)
				)
			)
		)
		(duplicate_pad_numbers_are_jumpers no)
		(fp_line
			(start 0.7874 -0.4064)
			(end 0.7874 0.4064)
			(stroke
				(width 0.1524)
				(type default)
			)
			(layer "F.SilkS")
		)
		(fp_line
			(start -0.7874 -0.4064)
			(end 0.7874 -0.4064)
			(stroke
				(width 0.1524)
				(type default)
			)
			(layer "F.SilkS")
		)
		(fp_line
			(start 0.7874 0.4064)
			(end -0.7874 0.4064)
			(stroke
				(width 0.1524)
				(type default)
			)
			(layer "F.SilkS")
		)
		(fp_line
			(start -0.7874 0.4064)
			(end -0.7874 -0.4064)
			(stroke
				(width 0.1524)
				(type default)
			)
			(layer "F.SilkS")
		)
		(fp_line
			(start -0.12065 -0.305054)
			(end -0.12065 -0.2794)
			(stroke
				(width 0.1)
				(type default)
			)
			(layer "F.Fab")
		)
		(fp_line
			(start -0.67945 -0.305054)
			(end -0.12065 -0.305054)
			(stroke
				(width 0.1)
				(type default)
			)
			(layer "F.Fab")
		)
		(fp_line
			(start 0.67945 -0.3048)
			(end 0.67945 0.3048)
			(stroke
				(width 0.1)
				(type default)
			)
			(layer "F.Fab")
		)
		(fp_line
			(start 0.12065 -0.3048)
			(end 0.67945 -0.3048)
			(stroke
				(width 0.1)
				(type default)
			)
			(layer "F.Fab")
		)
		(fp_line
			(start 0.12065 -0.2794)
			(end 0.12065 -0.3048)
			(stroke
				(width 0.1)
				(type default)
			)
			(layer "F.Fab")
		)
		(fp_line
			(start -0.12065 -0.2794)
			(end 0.12065 -0.2794)
			(stroke
				(width 0.1)
				(type default)
			)
			(layer "F.Fab")
		)
		(fp_line
			(start 0.120396 0.2794)
			(end -0.12065 0.2794)
			(stroke
				(width 0.1)
				(type default)
			)
			(layer "F.Fab")
		)
		(fp_line
			(start -0.12065 0.2794)
			(end -0.12065 0.3048)
			(stroke
				(width 0.1)
				(type default)
			)
			(layer "F.Fab")
		)
		(fp_line
			(start 0.67945 0.3048)
			(end 0.120396 0.3048)
			(stroke
				(width 0.1)
				(type default)
			)
			(layer "F.Fab")
		)
		(fp_line
			(start 0.120396 0.3048)
			(end 0.120396 0.2794)
			(stroke
				(width 0.1)
				(type default)
			)
			(layer "F.Fab")
		)
		(fp_line
			(start -0.12065 0.3048)
			(end -0.67945 0.3048)
			(stroke
				(width 0.1)
				(type default)
			)
			(layer "F.Fab")
		)
		(fp_line
			(start -0.67945 0.3048)
			(end -0.67945 -0.305054)
			(stroke
				(width 0.1)
				(type default)
			)
			(layer "F.Fab")
		)
		(pad "1" smd circle
			(at -0.40005 0 90)
			(size 0 0)
			(layers "F.Cu" "F.Mask" "F.Paste")
			(net "PVDDCR_CPU1_P0_VCCS")
		)
		(pad "2" smd circle
			(at 0.40005 0 90)
			(size 0 0)
			(layers "F.Cu" "F.Mask" "F.Paste")
			(net "GND")
		)
	)
	(footprint ""
		(layer "F.Cu")
		(at 187.071 -129.377948 90)
		(property "Reference" "R1203"
			(at 0 0 90)
			(layer "F.SilkS")
			(hide yes)
			(effects
				(font
					(size 1.27 1.27)
				)
			)
		)
		(property "Value" ""
			(at 0 0 90)
			(layer "F.Fab")
			(effects
				(font
					(size 1.27 1.27)
				)
			)
		)
		(duplicate_pad_numbers_are_jumpers no)
		(fp_line
			(start 0.7874 -0.4064)
			(end 0.7874 0.4064)
			(stroke
				(width 0.1524)
				(type default)
			)
			(layer "F.SilkS")
		)
		(fp_line
			(start -0.7874 -0.4064)
			(end 0.7874 -0.4064)
			(stroke
				(width 0.1524)
				(type default)
			)
			(layer "F.SilkS")
		)
		(fp_line
			(start 0.7874 0.4064)
			(end -0.7874 0.4064)
			(stroke
				(width 0.1524)
				(type default)
			)
			(layer "F.SilkS")
		)
		(fp_line
			(start -0.7874 0.4064)
			(end -0.7874 -0.4064)
			(stroke
				(width 0.1524)
				(type default)
			)
			(layer "F.SilkS")
		)
		(fp_line
			(start -0.12065 -0.305054)
			(end -0.12065 -0.2794)
			(stroke
				(width 0.1)
				(type default)
			)
			(layer "F.Fab")
		)
		(fp_line
			(start -0.67945 -0.305054)
			(end -0.12065 -0.305054)
			(stroke
				(width 0.1)
				(type default)
			)
			(layer "F.Fab")
		)
		(fp_line
			(start 0.67945 -0.3048)
			(end 0.67945 0.3048)
			(stroke
				(width 0.1)
				(type default)
			)
			(layer "F.Fab")
		)
		(fp_line
			(start 0.12065 -0.3048)
			(end 0.67945 -0.3048)
			(stroke
				(width 0.1)
				(type default)
			)
			(layer "F.Fab")
		)
		(fp_line
			(start 0.12065 -0.2794)
			(end 0.12065 -0.3048)
			(stroke
				(width 0.1)
				(type default)
			)
			(layer "F.Fab")
		)
		(fp_line
			(start -0.12065 -0.2794)
			(end 0.12065 -0.2794)
			(stroke
				(width 0.1)
				(type default)
			)
			(layer "F.Fab")
		)
		(fp_line
			(start 0.120396 0.2794)
			(end -0.12065 0.2794)
			(stroke
				(width 0.1)
				(type default)
			)
			(layer "F.Fab")
		)
		(fp_line
			(start -0.12065 0.2794)
			(end -0.12065 0.3048)
			(stroke
				(width 0.1)
				(type default)
			)
			(layer "F.Fab")
		)
		(fp_line
			(start 0.67945 0.3048)
			(end 0.120396 0.3048)
			(stroke
				(width 0.1)
				(type default)
			)
			(layer "F.Fab")
		)
		(fp_line
			(start 0.120396 0.3048)
			(end 0.120396 0.2794)
			(stroke
				(width 0.1)
				(type default)
			)
			(layer "F.Fab")
		)
		(fp_line
			(start -0.12065 0.3048)
			(end -0.67945 0.3048)
			(stroke
				(width 0.1)
				(type default)
			)
			(layer "F.Fab")
		)
		(fp_line
			(start -0.67945 0.3048)
			(end -0.67945 -0.305054)
			(stroke
				(width 0.1)
				(type default)
			)
			(layer "F.Fab")
		)
		(pad "1" smd circle
			(at -0.40005 0 90)
			(size 0 0)
			(layers "F.Cu" "F.Mask" "F.Paste")
			(net "BIOS_DEBUG_MODE_R")
		)
		(pad "2" smd circle
			(at 0.40005 0 90)
			(size 0 0)
			(layers "F.Cu" "F.Mask" "F.Paste")
			(net "BIOS_DEBUG_MODE")
		)
	)
	(footprint ""
		(layer "F.Cu")
		(at 22.010878 -16.099536 90)
		(property "Reference" "C683"
			(at 0 0 90)
			(layer "F.SilkS")
			(hide yes)
			(effects
				(font
					(size 1.27 1.27)
				)
			)
		)
		(property "Value" ""
			(at 0 0 90)
			(layer "F.Fab")
			(effects
				(font
					(size 1.27 1.27)
				)
			)
		)
		(duplicate_pad_numbers_are_jumpers no)
		(fp_line
			(start 0.299974 -0.150114)
			(end 0.299974 0.150114)
			(stroke
				(width 0.1)
				(type default)
			)
			(layer "F.Fab")
		)
		(fp_line
			(start -0.299974 -0.150114)
			(end 0.299974 -0.150114)
			(stroke
				(width 0.1)
				(type default)
			)
			(layer "F.Fab")
		)
		(fp_line
			(start 0.299974 0.150114)
			(end -0.299974 0.150114)
			(stroke
				(width 0.1)
				(type default)
			)
			(layer "F.Fab")
		)
		(fp_line
			(start -0.299974 0.150114)
			(end -0.299974 -0.150114)
			(stroke
				(width 0.1)
				(type default)
			)
			(layer "F.Fab")
		)
		(pad "1" smd rect
			(at -0.2667 0 90)
			(size 0.3048 0.381)
			(layers "F.Cu" "F.Mask" "F.Paste")
			(net "P5E_CPU1_G1_TX_C_DP<13>")
		)
		(pad "2" smd rect
			(at 0.2667 0 90)
			(size 0.3048 0.381)
			(layers "F.Cu" "F.Mask" "F.Paste")
			(net "P5E_CPU1_G1_TX_DP<13>")
		)
	)
)
